(kicad_pcb
	(version 20260206)
	(generator "pcbnew")
	(generator_version "10.0")
	(general
		(thickness 1.6)
		(legacy_teardrops no)
	)
	(paper "A4")
	(title_block
		(title "01162023_DA0F0TEBIF0_F0T_Expander_BD_F_brd_V02_OCP.brd")
		(comment 1 "Grand Teton / footprints 100-106 of 9728")
	)
	(layers
		(0 "F.Cu" signal "TOP")
		(4 "In1.Cu" signal "GND")
		(6 "In2.Cu" signal "VCC")
		(8 "In3.Cu" signal "VCC1")
		(10 "In4.Cu" signal "GND1")
		(12 "In5.Cu" signal "IN1")
		(14 "In6.Cu" signal "GND2")
		(16 "In7.Cu" signal "IN2")
		(18 "In8.Cu" signal "GND3")
		(20 "In9.Cu" signal "IN3")
		(22 "In10.Cu" signal "GND4")
		(24 "In11.Cu" signal "IN4")
		(26 "In12.Cu" signal "GND5")
		(28 "In13.Cu" signal "IN5")
		(30 "In14.Cu" signal "GND6")
		(32 "In15.Cu" signal "IN6")
		(34 "In16.Cu" signal "GND7")
		(2 "B.Cu" signal "BOTTOM")
		(9 "F.Adhes" user "F.Adhesive")
		(11 "B.Adhes" user "B.Adhesive")
		(13 "F.Paste" user "Package Geometry/Pastemask Top")
		(15 "B.Paste" user "Package Geometry/Pastemask Bottom")
		(5 "F.SilkS" user "Ref Des/Silkscreen Top")
		(7 "B.SilkS" user "Ref Des/Silkscreen Bottom")
		(1 "F.Mask" user "Board Geometry/Soldermask Top")
		(3 "B.Mask" user "Board Geometry/Soldermask Bottom")
		(17 "Dwgs.User" user "User.Drawings")
		(19 "Cmts.User" user "User.Comments")
		(21 "Eco1.User" user "User.Eco1")
		(23 "Eco2.User" user "User.Eco2")
		(25 "Edge.Cuts" user "Board Geometry/Outline")
		(27 "Margin" user)
		(31 "F.CrtYd" user "Package Geometry/Place Bound Top")
		(29 "B.CrtYd" user "Package Geometry/Place Bound Bottom")
		(35 "F.Fab" user "Ref Des/Assembly Top")
		(33 "B.Fab" user "Ref Des/Assembly Bottom")
	)
	(footprint ""
		(layer "F.Cu")
		(at 132.019802 -200.08342 90)
		(property "Reference" "C4495"
			(at 0 0 90)
			(layer "F.SilkS")
			(hide yes)
			(effects
				(font
					(size 1.27 1.27)
				)
			)
		)
		(property "Value" ""
			(at 0 0 90)
			(layer "F.Fab")
			(effects
				(font
					(size 1.27 1.27)
				)
			)
		)
		(duplicate_pad_numbers_are_jumpers no)
		(fp_line
			(start 0.7874 -0.4064)
			(end 0.7874 0.4064)
			(stroke
				(width 0.1524)
				(type default)
			)
			(layer "F.SilkS")
		)
		(fp_line
			(start -0.7874 -0.4064)
			(end 0.7874 -0.4064)
			(stroke
				(width 0.1524)
				(type default)
			)
			(layer "F.SilkS")
		)
		(fp_line
			(start 0.7874 0.4064)
			(end -0.7874 0.4064)
			(stroke
				(width 0.1524)
				(type default)
			)
			(layer "F.SilkS")
		)
		(fp_line
			(start -0.7874 0.4064)
			(end -0.7874 -0.4064)
			(stroke
				(width 0.1524)
				(type default)
			)
			(layer "F.SilkS")
		)
		(fp_line
			(start -0.12065 -0.305054)
			(end -0.12065 -0.2794)
			(stroke
				(width 0.1)
				(type default)
			)
			(layer "F.Fab")
		)
		(fp_line
			(start -0.67945 -0.305054)
			(end -0.12065 -0.305054)
			(stroke
				(width 0.1)
				(type default)
			)
			(layer "F.Fab")
		)
		(fp_line
			(start 0.67945 -0.3048)
			(end 0.67945 0.3048)
			(stroke
				(width 0.1)
				(type default)
			)
			(layer "F.Fab")
		)
		(fp_line
			(start 0.12065 -0.3048)
			(end 0.67945 -0.3048)
			(stroke
				(width 0.1)
				(type default)
			)
			(layer "F.Fab")
		)
		(fp_line
			(start 0.12065 -0.2794)
			(end 0.12065 -0.3048)
			(stroke
				(width 0.1)
				(type default)
			)
			(layer "F.Fab")
		)
		(fp_line
			(start -0.12065 -0.2794)
			(end 0.12065 -0.2794)
			(stroke
				(width 0.1)
				(type default)
			)
			(layer "F.Fab")
		)
		(fp_line
			(start 0.120396 0.2794)
			(end -0.12065 0.2794)
			(stroke
				(width 0.1)
				(type default)
			)
			(layer "F.Fab")
		)
		(fp_line
			(start -0.12065 0.2794)
			(end -0.12065 0.3048)
			(stroke
				(width 0.1)
				(type default)
			)
			(layer "F.Fab")
		)
		(fp_line
			(start 0.67945 0.3048)
			(end 0.120396 0.3048)
			(stroke
				(width 0.1)
				(type default)
			)
			(layer "F.Fab")
		)
		(fp_line
			(start 0.120396 0.3048)
			(end 0.120396 0.2794)
			(stroke
				(width 0.1)
				(type default)
			)
			(layer "F.Fab")
		)
		(fp_line
			(start -0.12065 0.3048)
			(end -0.67945 0.3048)
			(stroke
				(width 0.1)
				(type default)
			)
			(layer "F.Fab")
		)
		(fp_line
			(start -0.67945 0.3048)
			(end -0.67945 -0.305054)
			(stroke
				(width 0.1)
				(type default)
			)
			(layer "F.Fab")
		)
		(pad "1" smd circle
			(at -0.40005 0 90)
			(size 0 0)
			(layers "F.Cu" "F.Mask" "F.Paste")
			(net "NIC6_CLK_EN_R_N")
		)
		(pad "2" smd circle
			(at 0.40005 0 90)
			(size 0 0)
			(layers "F.Cu" "F.Mask" "F.Paste")
			(net "GND")
		)
	)
	(footprint ""
		(layer "F.Cu")
		(at 286.525462 -350.098614 90)
		(property "Reference" "C596"
			(at 0 0 90)
			(layer "F.SilkS")
			(hide yes)
			(effects
				(font
					(size 1.27 1.27)
				)
			)
		)
		(property "Value" ""
			(at 0 0 90)
			(layer "F.Fab")
			(effects
				(font
					(size 1.27 1.27)
				)
			)
		)
		(duplicate_pad_numbers_are_jumpers no)
		(fp_line
			(start 0.299974 -0.150114)
			(end 0.299974 0.150114)
			(stroke
				(width 0.1)
				(type default)
			)
			(layer "F.Fab")
		)
		(fp_line
			(start -0.299974 -0.150114)
			(end 0.299974 -0.150114)
			(stroke
				(width 0.1)
				(type default)
			)
			(layer "F.Fab")
		)
		(fp_line
			(start 0.299974 0.150114)
			(end -0.299974 0.150114)
			(stroke
				(width 0.1)
				(type default)
			)
			(layer "F.Fab")
		)
		(fp_line
			(start -0.299974 0.150114)
			(end -0.299974 -0.150114)
			(stroke
				(width 0.1)
				(type default)
			)
			(layer "F.Fab")
		)
		(pad "1" smd rect
			(at -0.2667 0 90)
			(size 0.3048 0.381)
			(layers "F.Cu" "F.Mask" "F.Paste")
			(net "P5E_PEX2_STN7_TX_DN<121>")
		)
		(pad "2" smd rect
			(at 0.2667 0 90)
			(size 0.3048 0.381)
			(layers "F.Cu" "F.Mask" "F.Paste")
			(net "P5E_PEX2_STN7_TX_C_DN<121>")
		)
	)
	(footprint ""
		(layer "F.Cu")
		(at 369.495578 -86.070694 180)
		(property "Reference" "R1606"
			(at 0 0 180)
			(layer "F.SilkS")
			(hide yes)
			(effects
				(font
					(size 1.27 1.27)
				)
			)
		)
		(property "Value" ""
			(at 0 0 180)
			(layer "F.Fab")
			(effects
				(font
					(size 1.27 1.27)
				)
			)
		)
		(duplicate_pad_numbers_are_jumpers no)
		(fp_line
			(start 0.7874 0.4064)
			(end -0.7874 0.4064)
			(stroke
				(width 0.1524)
				(type default)
			)
			(layer "F.SilkS")
		)
		(fp_line
			(start 0.7874 -0.4064)
			(end 0.7874 0.4064)
			(stroke
				(width 0.1524)
				(type default)
			)
			(layer "F.SilkS")
		)
		(fp_line
			(start -0.7874 0.4064)
			(end -0.7874 -0.4064)
			(stroke
				(width 0.1524)
				(type default)
			)
			(layer "F.SilkS")
		)
		(fp_line
			(start -0.7874 -0.4064)
			(end 0.7874 -0.4064)
			(stroke
				(width 0.1524)
				(type default)
			)
			(layer "F.SilkS")
		)
		(fp_line
			(start 0.67945 0.3048)
			(end 0.120396 0.3048)
			(stroke
				(width 0.1)
				(type default)
			)
			(layer "F.Fab")
		)
		(fp_line
			(start 0.67945 -0.3048)
			(end 0.67945 0.3048)
			(stroke
				(width 0.1)
				(type default)
			)
			(layer "F.Fab")
		)
		(fp_line
			(start 0.12065 -0.2794)
			(end 0.12065 -0.3048)
			(stroke
				(width 0.1)
				(type default)
			)
			(layer "F.Fab")
		)
		(fp_line
			(start 0.12065 -0.3048)
			(end 0.67945 -0.3048)
			(stroke
				(width 0.1)
				(type default)
			)
			(layer "F.Fab")
		)
		(fp_line
			(start 0.120396 0.3048)
			(end 0.120396 0.2794)
			(stroke
				(width 0.1)
				(type default)
			)
			(layer "F.Fab")
		)
		(fp_line
			(start 0.120396 0.2794)
			(end -0.12065 0.2794)
			(stroke
				(width 0.1)
				(type default)
			)
			(layer "F.Fab")
		)
		(fp_line
			(start -0.12065 0.3048)
			(end -0.67945 0.3048)
			(stroke
				(width 0.1)
				(type default)
			)
			(layer "F.Fab")
		)
		(fp_line
			(start -0.12065 0.2794)
			(end -0.12065 0.3048)
			(stroke
				(width 0.1)
				(type default)
			)
			(layer "F.Fab")
		)
		(fp_line
			(start -0.12065 -0.2794)
			(end 0.12065 -0.2794)
			(stroke
				(width 0.1)
				(type default)
			)
			(layer "F.Fab")
		)
		(fp_line
			(start -0.12065 -0.305054)
			(end -0.12065 -0.2794)
			(stroke
				(width 0.1)
				(type default)
			)
			(layer "F.Fab")
		)
		(fp_line
			(start -0.67945 0.3048)
			(end -0.67945 -0.305054)
			(stroke
				(width 0.1)
				(type default)
			)
			(layer "F.Fab")
		)
		(fp_line
			(start -0.67945 -0.305054)
			(end -0.12065 -0.305054)
			(stroke
				(width 0.1)
				(type default)
			)
			(layer "F.Fab")
		)
		(pad "1" smd circle
			(at -0.40005 0 180)
			(size 0 0)
			(layers "F.Cu" "F.Mask" "F.Paste")
			(net "P3V3_AUX")
		)
		(pad "2" smd circle
			(at 0.40005 0 180)
			(size 0 0)
			(layers "F.Cu" "F.Mask" "F.Paste")
			(net "SMB_BIC_I2C9_MUX1_SSD14_R_SDA")
		)
	)
	(footprint ""
		(layer "F.Cu")
		(at 415.487612 -343.952322 90)
		(property "Reference" "C820"
			(at 0 0 90)
			(layer "F.SilkS")
			(hide yes)
			(effects
				(font
					(size 1.27 1.27)
				)
			)
		)
		(property "Value" ""
			(at 0 0 90)
			(layer "F.Fab")
			(effects
				(font
					(size 1.27 1.27)
				)
			)
		)
		(duplicate_pad_numbers_are_jumpers no)
		(fp_line
			(start 0.299974 -0.150114)
			(end 0.299974 0.150114)
			(stroke
				(width 0.1)
				(type default)
			)
			(layer "F.Fab")
		)
		(fp_line
			(start -0.299974 -0.150114)
			(end 0.299974 -0.150114)
			(stroke
				(width 0.1)
				(type default)
			)
			(layer "F.Fab")
		)
		(fp_line
			(start 0.299974 0.150114)
			(end -0.299974 0.150114)
			(stroke
				(width 0.1)
				(type default)
			)
			(layer "F.Fab")
		)
		(fp_line
			(start -0.299974 0.150114)
			(end -0.299974 -0.150114)
			(stroke
				(width 0.1)
				(type default)
			)
			(layer "F.Fab")
		)
		(pad "1" smd rect
			(at -0.2667 0 90)
			(size 0.3048 0.381)
			(layers "F.Cu" "F.Mask" "F.Paste")
			(net "P5E_PEX3_STN7_TX_DP<114>")
		)
		(pad "2" smd rect
			(at 0.2667 0 90)
			(size 0.3048 0.381)
			(layers "F.Cu" "F.Mask" "F.Paste")
			(net "P5E_PEX3_STN7_TX_C_DP<114>")
		)
	)
	(footprint ""
		(layer "F.Cu")
		(at 217.235786 -224.398586 180)
		(property "Reference" "R1483"
			(at 0 0 180)
			(layer "F.SilkS")
			(hide yes)
			(effects
				(font
					(size 1.27 1.27)
				)
			)
		)
		(property "Value" ""
			(at 0 0 180)
			(layer "F.Fab")
			(effects
				(font
					(size 1.27 1.27)
				)
			)
		)
		(duplicate_pad_numbers_are_jumpers no)
		(fp_line
			(start 0.7874 0.4064)
			(end -0.7874 0.4064)
			(stroke
				(width 0.1524)
				(type default)
			)
			(layer "F.SilkS")
		)
		(fp_line
			(start 0.7874 -0.4064)
			(end 0.7874 0.4064)
			(stroke
				(width 0.1524)
				(type default)
			)
			(layer "F.SilkS")
		)
		(fp_line
			(start -0.7874 0.4064)
			(end -0.7874 -0.4064)
			(stroke
				(width 0.1524)
				(type default)
			)
			(layer "F.SilkS")
		)
		(fp_line
			(start -0.7874 -0.4064)
			(end 0.7874 -0.4064)
			(stroke
				(width 0.1524)
				(type default)
			)
			(layer "F.SilkS")
		)
		(fp_line
			(start 0.67945 0.3048)
			(end 0.120396 0.3048)
			(stroke
				(width 0.1)
				(type default)
			)
			(layer "F.Fab")
		)
		(fp_line
			(start 0.67945 -0.3048)
			(end 0.67945 0.3048)
			(stroke
				(width 0.1)
				(type default)
			)
			(layer "F.Fab")
		)
		(fp_line
			(start 0.12065 -0.2794)
			(end 0.12065 -0.3048)
			(stroke
				(width 0.1)
				(type default)
			)
			(layer "F.Fab")
		)
		(fp_line
			(start 0.12065 -0.3048)
			(end 0.67945 -0.3048)
			(stroke
				(width 0.1)
				(type default)
			)
			(layer "F.Fab")
		)
		(fp_line
			(start 0.120396 0.3048)
			(end 0.120396 0.2794)
			(stroke
				(width 0.1)
				(type default)
			)
			(layer "F.Fab")
		)
		(fp_line
			(start 0.120396 0.2794)
			(end -0.12065 0.2794)
			(stroke
				(width 0.1)
				(type default)
			)
			(layer "F.Fab")
		)
		(fp_line
			(start -0.12065 0.3048)
			(end -0.67945 0.3048)
			(stroke
				(width 0.1)
				(type default)
			)
			(layer "F.Fab")
		)
		(fp_line
			(start -0.12065 0.2794)
			(end -0.12065 0.3048)
			(stroke
				(width 0.1)
				(type default)
			)
			(layer "F.Fab")
		)
		(fp_line
			(start -0.12065 -0.2794)
			(end 0.12065 -0.2794)
			(stroke
				(width 0.1)
				(type default)
			)
			(layer "F.Fab")
		)
		(fp_line
			(start -0.12065 -0.305054)
			(end -0.12065 -0.2794)
			(stroke
				(width 0.1)
				(type default)
			)
			(layer "F.Fab")
		)
		(fp_line
			(start -0.67945 0.3048)
			(end -0.67945 -0.305054)
			(stroke
				(width 0.1)
				(type default)
			)
			(layer "F.Fab")
		)
		(fp_line
			(start -0.67945 -0.305054)
			(end -0.12065 -0.305054)
			(stroke
				(width 0.1)
				(type default)
			)
			(layer "F.Fab")
		)
		(pad "1" smd circle
			(at -0.40005 0 180)
			(size 0 0)
			(layers "F.Cu" "F.Mask" "F.Paste")
			(net "I3C_MB_SCL")
		)
		(pad "2" smd circle
			(at 0.40005 0 180)
			(size 0 0)
			(layers "F.Cu" "F.Mask" "F.Paste")
			(net "SMB_MB_I3C_ISO_SCL")
		)
	)
	(footprint ""
		(layer "F.Cu")
		(at 213.571582 -25.342342 -90)
		(property "Reference" "R430"
			(at 0 0 270)
			(layer "F.SilkS")
			(hide yes)
			(effects
				(font
					(size 1.27 1.27)
				)
			)
		)
		(property "Value" ""
			(at 0 0 270)
			(layer "F.Fab")
			(effects
				(font
					(size 1.27 1.27)
				)
			)
		)
		(duplicate_pad_numbers_are_jumpers no)
		(fp_line
			(start -0.7874 0.4064)
			(end -0.7874 -0.4064)
			(stroke
				(width 0.1524)
				(type default)
			)
			(layer "F.SilkS")
		)
		(fp_line
			(start 0.7874 0.4064)
			(end -0.7874 0.4064)
			(stroke
				(width 0.1524)
				(type default)
			)
			(layer "F.SilkS")
		)
		(fp_line
			(start -0.7874 -0.4064)
			(end 0.7874 -0.4064)
			(stroke
				(width 0.1524)
				(type default)
			)
			(layer "F.SilkS")
		)
		(fp_line
			(start 0.7874 -0.4064)
			(end 0.7874 0.4064)
			(stroke
				(width 0.1524)
				(type default)
			)
			(layer "F.SilkS")
		)
		(fp_line
			(start -0.67945 0.3048)
			(end -0.67945 -0.305054)
			(stroke
				(width 0.1)
				(type default)
			)
			(layer "F.Fab")
		)
		(fp_line
			(start -0.12065 0.3048)
			(end -0.67945 0.3048)
			(stroke
				(width 0.1)
				(type default)
			)
			(layer "F.Fab")
		)
		(fp_line
			(start 0.120396 0.3048)
			(end 0.120396 0.2794)
			(stroke
				(width 0.1)
				(type default)
			)
			(layer "F.Fab")
		)
		(fp_line
			(start 0.67945 0.3048)
			(end 0.120396 0.3048)
			(stroke
				(width 0.1)
				(type default)
			)
			(layer "F.Fab")
		)
		(fp_line
			(start -0.12065 0.2794)
			(end -0.12065 0.3048)
			(stroke
				(width 0.1)
				(type default)
			)
			(layer "F.Fab")
		)
		(fp_line
			(start 0.120396 0.2794)
			(end -0.12065 0.2794)
			(stroke
				(width 0.1)
				(type default)
			)
			(layer "F.Fab")
		)
		(fp_line
			(start -0.12065 -0.2794)
			(end 0.12065 -0.2794)
			(stroke
				(width 0.1)
				(type default)
			)
			(layer "F.Fab")
		)
		(fp_line
			(start 0.12065 -0.2794)
			(end 0.12065 -0.3048)
			(stroke
				(width 0.1)
				(type default)
			)
			(layer "F.Fab")
		)
		(fp_line
			(start 0.12065 -0.3048)
			(end 0.67945 -0.3048)
			(stroke
				(width 0.1)
				(type default)
			)
			(layer "F.Fab")
		)
		(fp_line
			(start 0.67945 -0.3048)
			(end 0.67945 0.3048)
			(stroke
				(width 0.1)
				(type default)
			)
			(layer "F.Fab")
		)
		(fp_line
			(start -0.67945 -0.305054)
			(end -0.12065 -0.305054)
			(stroke
				(width 0.1)
				(type default)
			)
			(layer "F.Fab")
		)
		(fp_line
			(start -0.12065 -0.305054)
			(end -0.12065 -0.2794)
			(stroke
				(width 0.1)
				(type default)
			)
			(layer "F.Fab")
		)
		(pad "1" smd circle
			(at -0.40005 0 270)
			(size 0 0)
			(layers "F.Cu" "F.Mask" "F.Paste")
			(net "P3V3_SSD7")
		)
		(pad "2" smd circle
			(at 0.40005 0 270)
			(size 0 0)
			(layers "F.Cu" "F.Mask" "F.Paste")
			(net "DUALPORT_N_SSD7")
		)
	)
	(footprint ""
		(layer "F.Cu")
		(at 337.471766 -280.44902 -90)
		(property "Reference" "PR149"
			(at 0 0 270)
			(layer "F.SilkS")
			(hide yes)
			(effects
				(font
					(size 1.27 1.27)
				)
			)
		)
		(property "Value" ""
			(at 0 0 270)
			(layer "F.Fab")
			(effects
				(font
					(size 1.27 1.27)
				)
			)
		)
		(duplicate_pad_numbers_are_jumpers no)
		(fp_line
			(start -0.7874 0.4064)
			(end -0.7874 -0.4064)
			(stroke
				(width 0.1524)
				(type default)
			)
			(layer "F.SilkS")
		)
		(fp_line
			(start 0.7874 0.4064)
			(end -0.7874 0.4064)
			(stroke
				(width 0.1524)
				(type default)
			)
			(layer "F.SilkS")
		)
		(fp_line
			(start -0.7874 -0.4064)
			(end 0.7874 -0.4064)
			(stroke
				(width 0.1524)
				(type default)
			)
			(layer "F.SilkS")
		)
		(fp_line
			(start 0.7874 -0.4064)
			(end 0.7874 0.4064)
			(stroke
				(width 0.1524)
				(type default)
			)
			(layer "F.SilkS")
		)
		(fp_line
			(start -0.67945 0.3048)
			(end -0.67945 -0.305054)
			(stroke
				(width 0.1)
				(type default)
			)
			(layer "F.Fab")
		)
		(fp_line
			(start -0.12065 0.3048)
			(end -0.67945 0.3048)
			(stroke
				(width 0.1)
				(type default)
			)
			(layer "F.Fab")
		)
		(fp_line
			(start 0.120396 0.3048)
			(end 0.120396 0.2794)
			(stroke
				(width 0.1)
				(type default)
			)
			(layer "F.Fab")
		)
		(fp_line
			(start 0.67945 0.3048)
			(end 0.120396 0.3048)
			(stroke
				(width 0.1)
				(type default)
			)
			(layer "F.Fab")
		)
		(fp_line
			(start -0.12065 0.2794)
			(end -0.12065 0.3048)
			(stroke
				(width 0.1)
				(type default)
			)
			(layer "F.Fab")
		)
		(fp_line
			(start 0.120396 0.2794)
			(end -0.12065 0.2794)
			(stroke
				(width 0.1)
				(type default)
			)
			(layer "F.Fab")
		)
		(fp_line
			(start -0.12065 -0.2794)
			(end 0.12065 -0.2794)
			(stroke
				(width 0.1)
				(type default)
			)
			(layer "F.Fab")
		)
		(fp_line
			(start 0.12065 -0.2794)
			(end 0.12065 -0.3048)
			(stroke
				(width 0.1)
				(type default)
			)
			(layer "F.Fab")
		)
		(fp_line
			(start 0.12065 -0.3048)
			(end 0.67945 -0.3048)
			(stroke
				(width 0.1)
				(type default)
			)
			(layer "F.Fab")
		)
		(fp_line
			(start 0.67945 -0.3048)
			(end 0.67945 0.3048)
			(stroke
				(width 0.1)
				(type default)
			)
			(layer "F.Fab")
		)
		(fp_line
			(start -0.67945 -0.305054)
			(end -0.12065 -0.305054)
			(stroke
				(width 0.1)
				(type default)
			)
			(layer "F.Fab")
		)
		(fp_line
			(start -0.12065 -0.305054)
			(end -0.12065 -0.2794)
			(stroke
				(width 0.1)
				(type default)
			)
			(layer "F.Fab")
		)
		(pad "1" smd circle
			(at -0.40005 0 270)
			(size 0 0)
			(layers "F.Cu" "F.Mask" "F.Paste")
			(net "SW_P0V8_PEX2_BOOT1")
		)
		(pad "2" smd circle
			(at 0.40005 0 270)
			(size 0 0)
			(layers "F.Cu" "F.Mask" "F.Paste")
			(net "SW_P0V8_PEX2_BOOT1_R")
		)
	)
)
